# BARRELEYE_G2-FPDB_POST-EVT-HW-EBOM-X00_20161123-add_2nd_source_X08-20161215-Final-b.xls — POP_GA (bom)
| FOXCONN TECHNOLOGY GROUP |  |  |  |  |  |  |  |  |  |  |  |  |
| BILL OF MATERIAL |  |  |  |  |  |  |  |  |  |  |  |  |
| REV OF  BOM |  | CUSTOMER | <name> |  | CUSTOMER P/N |  | PRODUCT CODE |  | PWA  REV |  | DATE |  |
| Sourcing (Single/Sole/Multi) | Critical Commodity (Y or N) | Component Class (1, 2, other) | Customer PSL (Y or N) | Item Number | Foxconn P/N | Customer P/N | Part Description | Manufacturer  Full Name | Manufacturer  Part Number | Qty | RoHS Status | Location |
